# T6G (Grand Teton) — schematic netlist excerpt (pin names and nets, part order shuffled) for the footprints in the layout excerpt that follows; sources: Cadence DE-HDL packaged netlist, KiCad conversion of 04192023_DAF0TMB3IC0_F0TG_MB_C_brd_V02_OCP.brd

U27  PCA9617ADP  IC  pkg TSSOP8_3XB  page 34
  VCCA  = PVDD18_S5_P0
  SCLA  = SMB_CPU0_4_SCL
  SDAA  = SMB_CPU0_4_SDA
  GND  = GND
  EN  = TP_U27_EN
  SDAB  = SMB_CPU0_4_XLTR_SDA
  SCLB  = SMB_CPU0_4_XLTR_SCL
  VCCB  = P3V3_AUX

C1115  Q_CAP  22UF 16V 20% EMPTY  pkg C0805  page 240 : A = PDB_PRSNT_R_N ; B = GND

(kicad_pcb
	(version 20260206)
	(generator "pcbnew")
	(generator_version "10.0")
	(general
		(thickness 1.6)
		(legacy_teardrops no)
	)
	(paper "A4")
	(title_block
		(title "04192023_DAF0TMB3IC0_F0TG_MB_C_brd_V02_OCP.brd")
		(comment 1 "Grand Teton / footprints 1308-1309 of 8354")
	)
	(layers
		(0 "F.Cu" signal "TOP")
		(4 "In1.Cu" signal "GND")
		(6 "In2.Cu" signal "IN1")
		(8 "In3.Cu" signal "GND1")
		(10 "In4.Cu" signal "IN2")
		(12 "In5.Cu" signal "GND2")
		(14 "In6.Cu" signal "IN3")
		(16 "In7.Cu" signal "GND3")
		(18 "In8.Cu" signal "VCC")
		(20 "In9.Cu" signal "VCC1")
		(22 "In10.Cu" signal "GND4")
		(24 "In11.Cu" signal "IN4")
		(26 "In12.Cu" signal "GND5")
		(28 "In13.Cu" signal "IN5")
		(30 "In14.Cu" signal "GND6")
		(32 "In15.Cu" signal "IN6")
		(34 "In16.Cu" signal "GND7")
		(2 "B.Cu" signal "BOTTOM")
		(9 "F.Adhes" user "F.Adhesive")
		(11 "B.Adhes" user "B.Adhesive")
		(13 "F.Paste" user "Package Geometry/Pastemask Top")
		(15 "B.Paste" user "Package Geometry/Pastemask Bottom")
		(5 "F.SilkS" user "Ref Des/Silkscreen Top")
		(7 "B.SilkS" user "Ref Des/Silkscreen Bottom")
		(1 "F.Mask" user "Board Geometry/Soldermask Top")
		(3 "B.Mask" user "Board Geometry/Soldermask Bottom")
		(17 "Dwgs.User" user "User.Drawings")
		(19 "Cmts.User" user "User.Comments")
		(21 "Eco1.User" user "User.Eco1")
		(23 "Eco2.User" user "User.Eco2")
		(25 "Edge.Cuts" user "Board Geometry/Outline")
		(27 "Margin" user)
		(31 "F.CrtYd" user "Package Geometry/Place Bound Top")
		(29 "B.CrtYd" user "Package Geometry/Place Bound Bottom")
		(35 "F.Fab" user "Ref Des/Assembly Top")
		(33 "B.Fab" user "Ref Des/Assembly Bottom")
	)
	(footprint ""
		(layer "F.Cu")
		(at 264.387076 -421.169084 180)
		(property "Reference" "C1115"
			(at 0 0 180)
			(layer "F.SilkS")
			(hide yes)
			(effects
				(font
					(size 1.27 1.27)
				)
			)
		)
		(property "Value" ""
			(at 0 0 180)
			(layer "F.Fab")
			(effects
				(font
					(size 1.27 1.27)
				)
			)
		)
		(duplicate_pad_numbers_are_jumpers no)
		(fp_line
			(start 1.524 0.762)
			(end -1.524 0.762)
			(stroke
				(width 0.1524)
				(type default)
			)
			(layer "F.SilkS")
		)
		(fp_line
			(start 1.524 -0.762)
			(end 1.524 0.762)
			(stroke
				(width 0.1524)
				(type default)
			)
			(layer "F.SilkS")
		)
		(fp_line
			(start -1.524 0.762)
			(end -1.524 -0.762)
			(stroke
				(width 0.1524)
				(type default)
			)
			(layer "F.SilkS")
		)
		(fp_line
			(start -1.524 -0.762)
			(end 1.524 -0.762)
			(stroke
				(width 0.1524)
				(type default)
			)
			(layer "F.SilkS")
		)
		(fp_line
			(start 1.1049 0.724916)
			(end 1.1049 -0.724916)
			(stroke
				(width 0.1)
				(type default)
			)
			(layer "F.Fab")
		)
		(fp_line
			(start 1.1049 -0.724916)
			(end -1.1049 -0.724916)
			(stroke
				(width 0.1)
				(type default)
			)
			(layer "F.Fab")
		)
		(fp_line
			(start -1.1049 0.724916)
			(end 1.1049 0.724916)
			(stroke
				(width 0.1)
				(type default)
			)
			(layer "F.Fab")
		)
		(fp_line
			(start -1.1049 -0.724916)
			(end -1.1049 0.724916)
			(stroke
				(width 0.1)
				(type default)
			)
			(layer "F.Fab")
		)
		(pad "1" smd rect
			(at -0.889 0)
			(size 1.016 1.27)
			(layers "F.Cu" "F.Mask" "F.Paste")
			(net "PDB_PRSNT_R_N")
		)
		(pad "2" smd rect
			(at 0.889 0)
			(size 1.016 1.27)
			(layers "F.Cu" "F.Mask" "F.Paste")
			(net "GND")
		)
	)
	(footprint ""
		(layer "F.Cu")
		(at 178.187604 -151.764238 -90)
		(property "Reference" "U27"
			(at 0.229108 -2.722118 0)
			(unlocked yes)
			(layer "F.SilkS")
			(effects
				(font
					(size 0.7874 0.5842)
					(thickness 0.1524)
				)
				(justify left)
			)
		)
		(property "Value" ""
			(at 0 0 270)
			(layer "F.Fab")
			(effects
				(font
					(size 1.27 1.27)
				)
			)
		)
		(duplicate_pad_numbers_are_jumpers no)
		(fp_line
			(start -1.463548 1.549908)
			(end -1.463548 -1.549908)
			(stroke
				(width 0.1524)
				(type default)
			)
			(layer "F.SilkS")
		)
		(fp_line
			(start 1.463548 1.549908)
			(end -1.463548 1.549908)
			(stroke
				(width 0.1524)
				(type default)
			)
			(layer "F.SilkS")
		)
		(fp_line
			(start 0 -0.762)
			(end 0.762 -1.549908)
			(stroke
				(width 0.1524)
				(type default)
			)
			(layer "F.SilkS")
		)
		(fp_line
			(start -1.463548 -1.549908)
			(end -0.787908 -1.549908)
			(stroke
				(width 0.1524)
				(type default)
			)
			(layer "F.SilkS")
		)
		(fp_line
			(start -0.787908 -1.549908)
			(end 0 -0.762)
			(stroke
				(width 0.1524)
				(type default)
			)
			(layer "F.SilkS")
		)
		(fp_line
			(start 0.762 -1.549908)
			(end 1.463548 -1.549908)
			(stroke
				(width 0.1524)
				(type default)
			)
			(layer "F.SilkS")
		)
		(fp_line
			(start 1.463548 -1.549908)
			(end 1.463548 1.549908)
			(stroke
				(width 0.1524)
				(type default)
			)
			(layer "F.SilkS")
		)
		(fp_poly
			(pts
				(xy -3.4798 -0.740156) (xy -3.4798 -1.359916) (xy -2.86004 -1.050036)
			)
			(stroke
				(width 0)
				(type default)
			)
			(fill yes)
			(layer "F.SilkS")
		)
		(fp_line
			(start -1.549908 1.549908)
			(end -1.549908 -1.549908)
			(stroke
				(width 0.1)
				(type default)
			)
			(layer "F.Fab")
		)
		(fp_line
			(start 1.549908 1.549908)
			(end -1.549908 1.549908)
			(stroke
				(width 0.1)
				(type default)
			)
			(layer "F.Fab")
		)
		(fp_line
			(start -1.549908 -1.549908)
			(end 1.549908 -1.549908)
			(stroke
				(width 0.1)
				(type default)
			)
			(layer "F.Fab")
		)
		(fp_line
			(start 1.549908 -1.549908)
			(end 1.549908 1.549908)
			(stroke
				(width 0.1)
				(type default)
			)
			(layer "F.Fab")
		)
		(fp_poly
			(pts
				(xy -3.4798 -1.359916) (xy -2.86004 -1.050036) (xy -3.4798 -0.740156)
			)
			(stroke
				(width 0)
				(type default)
			)
			(fill yes)
			(layer "F.Fab")
		)
		(pad "1" smd rect
			(at -2.175002 -1.050036)
			(size 0.6096 1.1684)
			(layers "F.Cu" "F.Mask" "F.Paste")
			(net "PVDD18_S5_P0")
		)
		(pad "2" smd rect
			(at -2.175002 -0.32512)
			(size 0.4318 1.1684)
			(layers "F.Cu" "F.Mask" "F.Paste")
			(net "SMB_CPU0_4_SCL")
		)
		(pad "3" smd rect
			(at -2.175002 0.32512)
			(size 0.4318 1.1684)
			(layers "F.Cu" "F.Mask" "F.Paste")
			(net "SMB_CPU0_4_SDA")
		)
		(pad "4" smd rect
			(at -2.175002 1.050036)
			(size 0.6096 1.1684)
			(layers "F.Cu" "F.Mask" "F.Paste")
			(net "GND")
		)
		(pad "5" smd rect
			(at 2.175002 1.050036)
			(size 0.6096 1.1684)
			(layers "F.Cu" "F.Mask" "F.Paste")
			(net "TP_U27_EN")
		)
		(pad "6" smd rect
			(at 2.175002 0.32512)
			(size 0.4318 1.1684)
			(layers "F.Cu" "F.Mask" "F.Paste")
			(net "SMB_CPU0_4_XLTR_SDA")
		)
		(pad "7" smd rect
			(at 2.175002 -0.32512)
			(size 0.4318 1.1684)
			(layers "F.Cu" "F.Mask" "F.Paste")
			(net "SMB_CPU0_4_XLTR_SCL")
		)
		(pad "8" smd rect
			(at 2.175002 -1.050036)
			(size 0.6096 1.1684)
			(layers "F.Cu" "F.Mask" "F.Paste")
			(net "P3V3_AUX")
		)
	)
)
